FILE_TYPE = MACRO_DRAWING;
SET COLOR_WIRE YELLOW;
SET COLOR_PROP ORANGE;
SET COLOR_DOT WHITE;
SET COLOR_ARC YELLOW;
SET COLOR_BODY GREEN;
SET COLOR_NOTE PURPLE;
SET PROP_DISPLAY VALUE;
SET PAGE_NUMBER P437;
FORCEADD PT5161LRS..8
(-7550 4100);
FORCEPROP 1 LAST LOCATION U6014
J 0
(-7900 5725);
DISPLAY 0.723404 (-7900 5725);
PAINT GREEN (-7900 5725);
FORCEPROP 0 LAST $SEC 8
J 0
(-7900 5875);
DISPLAY 0.680851 (-7900 5875);
PAINT MONO (-7900 5875);
DISPLAY INVISIBLE (-7900 5875);
FORCEPROP 0 LAST CDS_SEC 8
J 0
(-7900 5875);
DISPLAY 0.680851 (-7900 5875);
DISPLAY INVISIBLE (-7900 5875);
FORCEPROP 0 LASTPIN (-7100 5250) $PN R35
J 0
(-7090 5260);
DISPLAY 0.680851 (-7090 5260);
PAINT MONO (-7090 5260);
FORCEPROP 0 LASTPIN (-7100 4900) $PN AB35
J 0
(-7090 4910);
DISPLAY 0.680851 (-7090 4910);
PAINT MONO (-7090 4910);
FORCEPROP 0 LASTPIN (-7100 4550) $PN AJ35
J 0
(-7090 4560);
DISPLAY 0.680851 (-7090 4560);
PAINT MONO (-7090 4560);
FORCEPROP 0 LASTPIN (-7100 4200) $PN AT35
J 0
(-7090 4210);
DISPLAY 0.680851 (-7090 4210);
PAINT MONO (-7090 4210);
FORCEPROP 0 LASTPIN (-7100 3850) $PN BC35
J 0
(-7090 3860);
DISPLAY 0.680851 (-7090 3860);
PAINT MONO (-7090 3860);
FORCEPROP 0 LASTPIN (-7100 3500) $PN BK35
J 0
(-7090 3510);
DISPLAY 0.680851 (-7090 3510);
PAINT MONO (-7090 3510);
FORCEPROP 0 LASTPIN (-7100 3150) $PN BU35
J 0
(-7090 3160);
DISPLAY 0.680851 (-7090 3160);
PAINT MONO (-7090 3160);
FORCEPROP 0 LASTPIN (-7100 2800) $PN CD35
J 0
(-7090 2810);
DISPLAY 0.680851 (-7090 2810);
PAINT MONO (-7090 2810);
FORCEPROP 0 LASTPIN (-7100 5350) $PN N34
J 0
(-7090 5360);
DISPLAY 0.680851 (-7090 5360);
PAINT MONO (-7090 5360);
FORCEPROP 0 LASTPIN (-7100 5000) $PN Y34
J 0
(-7090 5010);
DISPLAY 0.680851 (-7090 5010);
PAINT MONO (-7090 5010);
FORCEPROP 0 LASTPIN (-7100 4650) $PN AG34
J 0
(-7090 4660);
DISPLAY 0.680851 (-7090 4660);
PAINT MONO (-7090 4660);
FORCEPROP 0 LASTPIN (-7100 4300) $PN AP34
J 0
(-7090 4310);
DISPLAY 0.680851 (-7090 4310);
PAINT MONO (-7090 4310);
FORCEPROP 0 LASTPIN (-7100 3950) $PN BA34
J 0
(-7090 3960);
DISPLAY 0.680851 (-7090 3960);
PAINT MONO (-7090 3960);
FORCEPROP 0 LASTPIN (-7100 3600) $PN BH34
J 0
(-7090 3610);
DISPLAY 0.680851 (-7090 3610);
PAINT MONO (-7090 3610);
FORCEPROP 0 LASTPIN (-7100 3250) $PN BR34
J 0
(-7090 3260);
DISPLAY 0.680851 (-7090 3260);
PAINT MONO (-7090 3260);
FORCEPROP 0 LASTPIN (-7100 2900) $PN CB34
J 0
(-7090 2910);
DISPLAY 0.680851 (-7090 2910);
PAINT MONO (-7090 2910);
FORCEPROP 2 LAST PART_TYPE SMLF
J 0
(-7900 5825);
DISPLAY 0.680851 (-7900 5825);
FORCEPROP 2 LAST VALUE PT5161LRS
J 0
(-7900 5775);
DISPLAY 0.680851 (-7900 5775);
FORCEPROP 1 LAST MATERIAL IC
J 0
(-7900 5575);
DISPLAY 0.723404 (-7900 5575);
PAINT GREEN (-7900 5575);
FORCEPROP 2 LAST CDS_LIB pure_quanta
J 0
(-7550 4100);
DISPLAY INVISIBLE (-7550 4100);
FORCEPROP 1 LAST CDS_LMAN_SYM_OUTLINE -350,1450,300,-1400
J 0
(-7550 4100);
DISPLAY 0.468085 (-7550 4100);
PAINT GREEN (-7550 4100);
DISPLAY INVISIBLE (-7550 4100);
FORCEPROP 1 LAST NEEDS_NO_SIZE TRUE
J 0
(-7550 4100);
DISPLAY 0.723404 (-7550 4100);
PAINT GREEN (-7550 4100);
DISPLAY INVISIBLE (-7550 4100);
FORCEPROP 1 LAST PATH I1
J 0
(-7550 4100);
DISPLAY 0.723404 (-7550 4100);
PAINT GREEN (-7550 4100);
DISPLAY INVISIBLE (-7550 4100);
FORCEPROP 1 LAST PART_NUMBER AJ051610U03
J 0
(-7900 5650);
DISPLAY 0.723404 (-7900 5650);
PAINT GREEN (-7900 5650);
DISPLAY INVISIBLE (-7900 5650);
FORCEADD TAP..1
(-6525 4300);
FORCEPROP 3 LASTPIN (-6575 4300) SIG_NAME P5E_CPU1_P0_TX_C_DN<12>
J 0
(-6565 4310);
DISPLAY 0.659574 (-6565 4310);
PAINT MONO (-6565 4310);
DISPLAY INVISIBLE (-6565 4310);
FORCEPROP 1 LASTPIN (-6575 4300) BN 12
J 0
(-6587 4308);
DISPLAY 0.680851 (-6587 4308);
PAINT GREEN (-6587 4308);
FORCEPROP 2 LAST CDS_LIB standard
J 0
(-6525 4300);
DISPLAY INVISIBLE (-6525 4300);
FORCEPROP 1 LAST BODY_TYPE PLUMBING
J 0
(-6525 4350);
DISPLAY 0.872340 (-6525 4350);
PAINT GREEN (-6525 4350);
DISPLAY INVISIBLE (-6525 4350);
FORCEPROP 1 LAST HDL_TAP TRUE
J 0
(-6200 4175);
DISPLAY 0.872340 (-6200 4175);
DISPLAY INVISIBLE (-6200 4175);
FORCEPROP 1 LAST PATH I10
J 0
(-6527 4300);
DISPLAY 0.872340 (-6527 4300);
PAINT GREEN (-6527 4300);
DISPLAY INVISIBLE (-6527 4300);
FORCEADD TAP..1
(-6325 4200);
FORCEPROP 3 LASTPIN (-6375 4200) SIG_NAME P5E_CPU1_P0_TX_C_DP<12>
J 0
(-6365 4210);
DISPLAY 0.659574 (-6365 4210);
PAINT MONO (-6365 4210);
DISPLAY INVISIBLE (-6365 4210);
FORCEPROP 1 LASTPIN (-6375 4200) BN 12
J 0
(-6387 4208);
DISPLAY 0.680851 (-6387 4208);
PAINT GREEN (-6387 4208);
FORCEPROP 2 LAST CDS_LIB standard
J 0
(-6325 4200);
DISPLAY INVISIBLE (-6325 4200);
FORCEPROP 1 LAST BODY_TYPE PLUMBING
J 0
(-6325 4250);
DISPLAY 0.872340 (-6325 4250);
PAINT GREEN (-6325 4250);
DISPLAY INVISIBLE (-6325 4250);
FORCEPROP 1 LAST HDL_TAP TRUE
J 0
(-6000 4075);
DISPLAY 0.872340 (-6000 4075);
DISPLAY INVISIBLE (-6000 4075);
FORCEPROP 1 LAST PATH I11
J 0
(-6327 4200);
DISPLAY 0.872340 (-6327 4200);
PAINT GREEN (-6327 4200);
DISPLAY INVISIBLE (-6327 4200);
FORCEADD TAP..1
(-6525 4550);
FORCEPROP 3 LASTPIN (-6575 4550) SIG_NAME P5E_CPU1_P0_TX_C_DN<13>
J 0
(-6565 4560);
DISPLAY 0.659574 (-6565 4560);
PAINT MONO (-6565 4560);
DISPLAY INVISIBLE (-6565 4560);
FORCEPROP 1 LASTPIN (-6575 4550) BN 13
J 0
(-6587 4558);
DISPLAY 0.680851 (-6587 4558);
PAINT GREEN (-6587 4558);
FORCEPROP 2 LAST CDS_LIB standard
J 0
(-6525 4550);
DISPLAY INVISIBLE (-6525 4550);
FORCEPROP 1 LAST BODY_TYPE PLUMBING
J 0
(-6525 4600);
DISPLAY 0.872340 (-6525 4600);
PAINT GREEN (-6525 4600);
DISPLAY INVISIBLE (-6525 4600);
FORCEPROP 1 LAST HDL_TAP TRUE
J 0
(-6200 4425);
DISPLAY 0.872340 (-6200 4425);
DISPLAY INVISIBLE (-6200 4425);
FORCEPROP 1 LAST PATH I12
J 0
(-6527 4550);
DISPLAY 0.872340 (-6527 4550);
PAINT GREEN (-6527 4550);
DISPLAY INVISIBLE (-6527 4550);
FORCEADD TAP..1
(-6325 4650);
FORCEPROP 3 LASTPIN (-6375 4650) SIG_NAME P5E_CPU1_P0_TX_C_DP<13>
J 0
(-6365 4660);
DISPLAY 0.659574 (-6365 4660);
PAINT MONO (-6365 4660);
DISPLAY INVISIBLE (-6365 4660);
FORCEPROP 1 LASTPIN (-6375 4650) BN 13
J 0
(-6387 4658);
DISPLAY 0.680851 (-6387 4658);
PAINT GREEN (-6387 4658);
FORCEPROP 2 LAST CDS_LIB standard
J 0
(-6325 4650);
DISPLAY INVISIBLE (-6325 4650);
FORCEPROP 1 LAST BODY_TYPE PLUMBING
J 0
(-6325 4700);
DISPLAY 0.872340 (-6325 4700);
PAINT GREEN (-6325 4700);
DISPLAY INVISIBLE (-6325 4700);
FORCEPROP 1 LAST HDL_TAP TRUE
J 0
(-6000 4525);
DISPLAY 0.872340 (-6000 4525);
DISPLAY INVISIBLE (-6000 4525);
FORCEPROP 1 LAST PATH I13
J 0
(-6327 4650);
DISPLAY 0.872340 (-6327 4650);
PAINT GREEN (-6327 4650);
DISPLAY INVISIBLE (-6327 4650);
FORCEADD TAP..1
(-6325 4900);
FORCEPROP 3 LASTPIN (-6375 4900) SIG_NAME P5E_CPU1_P0_TX_C_DP<14>
J 0
(-6365 4910);
DISPLAY 0.659574 (-6365 4910);
PAINT MONO (-6365 4910);
DISPLAY INVISIBLE (-6365 4910);
FORCEPROP 1 LASTPIN (-6375 4900) BN 14
J 0
(-6387 4908);
DISPLAY 0.680851 (-6387 4908);
PAINT GREEN (-6387 4908);
FORCEPROP 2 LAST CDS_LIB standard
J 0
(-6325 4900);
DISPLAY INVISIBLE (-6325 4900);
FORCEPROP 1 LAST BODY_TYPE PLUMBING
J 0
(-6325 4950);
DISPLAY 0.872340 (-6325 4950);
PAINT GREEN (-6325 4950);
DISPLAY INVISIBLE (-6325 4950);
FORCEPROP 1 LAST HDL_TAP TRUE
J 0
(-6000 4775);
DISPLAY 0.872340 (-6000 4775);
DISPLAY INVISIBLE (-6000 4775);
FORCEPROP 1 LAST PATH I14
J 0
(-6327 4900);
DISPLAY 0.872340 (-6327 4900);
PAINT GREEN (-6327 4900);
DISPLAY INVISIBLE (-6327 4900);
FORCEADD TAP..1
(-6525 5000);
FORCEPROP 3 LASTPIN (-6575 5000) SIG_NAME P5E_CPU1_P0_TX_C_DN<14>
J 0
(-6565 5010);
DISPLAY 0.659574 (-6565 5010);
PAINT MONO (-6565 5010);
DISPLAY INVISIBLE (-6565 5010);
FORCEPROP 1 LASTPIN (-6575 5000) BN 14
J 0
(-6587 5008);
DISPLAY 0.680851 (-6587 5008);
PAINT GREEN (-6587 5008);
FORCEPROP 2 LAST CDS_LIB standard
J 0
(-6525 5000);
DISPLAY INVISIBLE (-6525 5000);
FORCEPROP 1 LAST BODY_TYPE PLUMBING
J 0
(-6525 5050);
DISPLAY 0.872340 (-6525 5050);
PAINT GREEN (-6525 5050);
DISPLAY INVISIBLE (-6525 5050);
FORCEPROP 1 LAST HDL_TAP TRUE
J 0
(-6200 4875);
DISPLAY 0.872340 (-6200 4875);
DISPLAY INVISIBLE (-6200 4875);
FORCEPROP 1 LAST PATH I15
J 0
(-6527 5000);
DISPLAY 0.872340 (-6527 5000);
PAINT GREEN (-6527 5000);
DISPLAY INVISIBLE (-6527 5000);
FORCEADD TAP..1
(-6525 5350);
FORCEPROP 3 LASTPIN (-6575 5350) SIG_NAME P5E_CPU1_P0_TX_C_DN<15>
J 0
(-6565 5360);
DISPLAY 0.659574 (-6565 5360);
PAINT MONO (-6565 5360);
DISPLAY INVISIBLE (-6565 5360);
FORCEPROP 1 LASTPIN (-6575 5350) BN 15
J 0
(-6587 5358);
DISPLAY 0.680851 (-6587 5358);
PAINT GREEN (-6587 5358);
FORCEPROP 2 LAST CDS_LIB standard
J 0
(-6525 5350);
DISPLAY INVISIBLE (-6525 5350);
FORCEPROP 1 LAST BODY_TYPE PLUMBING
J 0
(-6525 5400);
DISPLAY 0.872340 (-6525 5400);
PAINT GREEN (-6525 5400);
DISPLAY INVISIBLE (-6525 5400);
FORCEPROP 1 LAST HDL_TAP TRUE
J 0
(-6200 5225);
DISPLAY 0.872340 (-6200 5225);
DISPLAY INVISIBLE (-6200 5225);
FORCEPROP 1 LAST PATH I16
J 0
(-6527 5350);
DISPLAY 0.872340 (-6527 5350);
PAINT GREEN (-6527 5350);
DISPLAY INVISIBLE (-6527 5350);
FORCEADD TAP..1
(-6325 5250);
FORCEPROP 3 LASTPIN (-6375 5250) SIG_NAME P5E_CPU1_P0_TX_C_DP<15>
J 0
(-6365 5260);
DISPLAY 0.659574 (-6365 5260);
PAINT MONO (-6365 5260);
DISPLAY INVISIBLE (-6365 5260);
FORCEPROP 1 LASTPIN (-6375 5250) BN 15
J 0
(-6387 5258);
DISPLAY 0.680851 (-6387 5258);
PAINT GREEN (-6387 5258);
FORCEPROP 2 LAST CDS_LIB standard
J 0
(-6325 5250);
DISPLAY INVISIBLE (-6325 5250);
FORCEPROP 1 LAST BODY_TYPE PLUMBING
J 0
(-6325 5300);
DISPLAY 0.872340 (-6325 5300);
PAINT GREEN (-6325 5300);
DISPLAY INVISIBLE (-6325 5300);
FORCEPROP 1 LAST HDL_TAP TRUE
J 0
(-6000 5125);
DISPLAY 0.872340 (-6000 5125);
DISPLAY INVISIBLE (-6000 5125);
FORCEPROP 1 LAST PATH I17
J 0
(-6327 5250);
DISPLAY 0.872340 (-6327 5250);
PAINT GREEN (-6327 5250);
DISPLAY INVISIBLE (-6327 5250);
FORCEADD OFFPAGE..1
R 2
(-5325 5275);
FORCEPROP 2 LAST $XR0 65 
J 0
(-5139 5275);
DISPLAY 0.638298 (-5139 5275);
PAINT MONO (-5139 5275);
FORCEPROP 2 LAST CDS_LIB standard
J 0
(-5325 5275);
DISPLAY INVISIBLE (-5325 5275);
FORCEPROP 1 LAST OFFPAGE TRUE
J 2
(-5650 5150);
DISPLAY 0.872340 (-5650 5150);
DISPLAY INVISIBLE (-5650 5150);
FORCEPROP 1 LAST COMMENT_BODY TRUE
J 2
(-5450 5175);
DISPLAY 0.872340 (-5450 5175);
PAINT GREEN (-5450 5175);
DISPLAY INVISIBLE (-5450 5175);
FORCEPROP 2 LAST PATH I18
J 0
(-5150 5350);
DISPLAY 0.680851 (-5150 5350);
DISPLAY INVISIBLE (-5150 5350);
FORCEADD OFFPAGE..1
R 2
(-5325 5375);
FORCEPROP 2 LAST $XR0 65 
J 0
(-5139 5375);
DISPLAY 0.638298 (-5139 5375);
PAINT MONO (-5139 5375);
FORCEPROP 2 LAST CDS_LIB standard
J 2
(-5325 5375);
DISPLAY INVISIBLE (-5325 5375);
FORCEPROP 1 LAST OFFPAGE TRUE
J 2
(-5650 5250);
DISPLAY 0.872340 (-5650 5250);
DISPLAY INVISIBLE (-5650 5250);
FORCEPROP 1 LAST COMMENT_BODY TRUE
J 2
(-5450 5275);
DISPLAY 0.872340 (-5450 5275);
PAINT GREEN (-5450 5275);
DISPLAY INVISIBLE (-5450 5275);
FORCEPROP 2 LAST PATH I19
J 0
(-5150 5450);
DISPLAY 0.680851 (-5150 5450);
DISPLAY INVISIBLE (-5150 5450);
FORCEADD TAP..1
(-6325 2800);
FORCEPROP 3 LASTPIN (-6375 2800) SIG_NAME P5E_CPU1_P0_TX_C_DP<8>
J 0
(-6365 2810);
DISPLAY 0.659574 (-6365 2810);
PAINT MONO (-6365 2810);
DISPLAY INVISIBLE (-6365 2810);
FORCEPROP 1 LASTPIN (-6375 2800) BN 8
J 0
(-6387 2808);
DISPLAY 0.680851 (-6387 2808);
PAINT GREEN (-6387 2808);
FORCEPROP 2 LAST CDS_LIB standard
J 0
(-6325 2800);
DISPLAY INVISIBLE (-6325 2800);
FORCEPROP 1 LAST BODY_TYPE PLUMBING
J 0
(-6325 2850);
DISPLAY 0.872340 (-6325 2850);
PAINT GREEN (-6325 2850);
DISPLAY INVISIBLE (-6325 2850);
FORCEPROP 1 LAST HDL_TAP TRUE
J 0
(-6000 2675);
DISPLAY 0.872340 (-6000 2675);
DISPLAY INVISIBLE (-6000 2675);
FORCEPROP 1 LAST PATH I2
J 0
(-6327 2800);
DISPLAY 0.872340 (-6327 2800);
PAINT GREEN (-6327 2800);
DISPLAY INVISIBLE (-6327 2800);
FORCEADD TAP..1
(-1900 2850);
FORCEPROP 3 LASTPIN (-1950 2850) SIG_NAME P5E_CPU1_P0_TX_C_DN<0>
J 0
(-1940 2860);
DISPLAY 0.659574 (-1940 2860);
PAINT MONO (-1940 2860);
DISPLAY INVISIBLE (-1940 2860);
FORCEPROP 1 LASTPIN (-1950 2850) BN 0
J 0
(-1962 2858);
DISPLAY 0.680851 (-1962 2858);
PAINT GREEN (-1962 2858);
FORCEPROP 2 LAST CDS_LIB standard
J 0
(-1900 2850);
DISPLAY INVISIBLE (-1900 2850);
FORCEPROP 1 LAST BODY_TYPE PLUMBING
J 0
(-1900 2900);
DISPLAY 0.872340 (-1900 2900);
PAINT GREEN (-1900 2900);
DISPLAY INVISIBLE (-1900 2900);
FORCEPROP 1 LAST HDL_TAP TRUE
J 0
(-1575 2725);
DISPLAY 0.872340 (-1575 2725);
DISPLAY INVISIBLE (-1575 2725);
FORCEPROP 1 LAST PATH I20
J 0
(-1902 2850);
DISPLAY 0.872340 (-1902 2850);
PAINT GREEN (-1902 2850);
DISPLAY INVISIBLE (-1902 2850);
FORCEADD TAP..1
(-1700 2750);
FORCEPROP 3 LASTPIN (-1750 2750) SIG_NAME P5E_CPU1_P0_TX_C_DP<0>
J 0
(-1740 2760);
DISPLAY 0.659574 (-1740 2760);
PAINT MONO (-1740 2760);
DISPLAY INVISIBLE (-1740 2760);
FORCEPROP 1 LASTPIN (-1750 2750) BN 0
J 0
(-1762 2758);
DISPLAY 0.680851 (-1762 2758);
PAINT GREEN (-1762 2758);
FORCEPROP 2 LAST CDS_LIB standard
J 0
(-1700 2750);
DISPLAY INVISIBLE (-1700 2750);
FORCEPROP 1 LAST BODY_TYPE PLUMBING
J 0
(-1700 2800);
DISPLAY 0.872340 (-1700 2800);
PAINT GREEN (-1700 2800);
DISPLAY INVISIBLE (-1700 2800);
FORCEPROP 1 LAST HDL_TAP TRUE
J 0
(-1375 2625);
DISPLAY 0.872340 (-1375 2625);
DISPLAY INVISIBLE (-1375 2625);
FORCEPROP 1 LAST PATH I21
J 0
(-1702 2750);
DISPLAY 0.872340 (-1702 2750);
PAINT GREEN (-1702 2750);
DISPLAY INVISIBLE (-1702 2750);
FORCEADD TAP..1
(-1900 3100);
FORCEPROP 3 LASTPIN (-1950 3100) SIG_NAME P5E_CPU1_P0_TX_C_DN<1>
J 0
(-1940 3110);
DISPLAY 0.659574 (-1940 3110);
PAINT MONO (-1940 3110);
DISPLAY INVISIBLE (-1940 3110);
FORCEPROP 1 LASTPIN (-1950 3100) BN 1
J 0
(-1962 3108);
DISPLAY 0.680851 (-1962 3108);
PAINT GREEN (-1962 3108);
FORCEPROP 2 LAST CDS_LIB standard
J 0
(-1900 3100);
DISPLAY INVISIBLE (-1900 3100);
FORCEPROP 1 LAST BODY_TYPE PLUMBING
J 0
(-1900 3150);
DISPLAY 0.872340 (-1900 3150);
PAINT GREEN (-1900 3150);
DISPLAY INVISIBLE (-1900 3150);
FORCEPROP 1 LAST HDL_TAP TRUE
J 0
(-1575 2975);
DISPLAY 0.872340 (-1575 2975);
DISPLAY INVISIBLE (-1575 2975);
FORCEPROP 1 LAST PATH I22
J 0
(-1902 3100);
DISPLAY 0.872340 (-1902 3100);
PAINT GREEN (-1902 3100);
DISPLAY INVISIBLE (-1902 3100);
FORCEADD TAP..1
(-1700 3200);
FORCEPROP 3 LASTPIN (-1750 3200) SIG_NAME P5E_CPU1_P0_TX_C_DP<1>
J 0
(-1740 3210);
DISPLAY 0.659574 (-1740 3210);
PAINT MONO (-1740 3210);
DISPLAY INVISIBLE (-1740 3210);
FORCEPROP 1 LASTPIN (-1750 3200) BN 1
J 0
(-1762 3208);
DISPLAY 0.680851 (-1762 3208);
PAINT GREEN (-1762 3208);
FORCEPROP 2 LAST CDS_LIB standard
J 0
(-1700 3200);
DISPLAY INVISIBLE (-1700 3200);
FORCEPROP 1 LAST BODY_TYPE PLUMBING
J 0
(-1700 3250);
DISPLAY 0.872340 (-1700 3250);
PAINT GREEN (-1700 3250);
DISPLAY INVISIBLE (-1700 3250);
FORCEPROP 1 LAST HDL_TAP TRUE
J 0
(-1375 3075);
DISPLAY 0.872340 (-1375 3075);
DISPLAY INVISIBLE (-1375 3075);
FORCEPROP 1 LAST PATH I23
J 0
(-1702 3200);
DISPLAY 0.872340 (-1702 3200);
PAINT GREEN (-1702 3200);
DISPLAY INVISIBLE (-1702 3200);
FORCEADD TAP..1
(-1900 3550);
FORCEPROP 3 LASTPIN (-1950 3550) SIG_NAME P5E_CPU1_P0_TX_C_DN<2>
J 0
(-1940 3560);
DISPLAY 0.659574 (-1940 3560);
PAINT MONO (-1940 3560);
DISPLAY INVISIBLE (-1940 3560);
FORCEPROP 1 LASTPIN (-1950 3550) BN 2
J 0
(-1962 3558);
DISPLAY 0.680851 (-1962 3558);
PAINT GREEN (-1962 3558);
FORCEPROP 2 LAST CDS_LIB standard
J 0
(-1900 3550);
DISPLAY INVISIBLE (-1900 3550);
FORCEPROP 1 LAST BODY_TYPE PLUMBING
J 0
(-1900 3600);
DISPLAY 0.872340 (-1900 3600);
PAINT GREEN (-1900 3600);
DISPLAY INVISIBLE (-1900 3600);
FORCEPROP 1 LAST HDL_TAP TRUE
J 0
(-1575 3425);
DISPLAY 0.872340 (-1575 3425);
DISPLAY INVISIBLE (-1575 3425);
FORCEPROP 1 LAST PATH I24
J 0
(-1902 3550);
DISPLAY 0.872340 (-1902 3550);
PAINT GREEN (-1902 3550);
DISPLAY INVISIBLE (-1902 3550);
FORCEADD TAP..1
(-1900 3900);
FORCEPROP 3 LASTPIN (-1950 3900) SIG_NAME P5E_CPU1_P0_TX_C_DN<3>
J 0
(-1940 3910);
DISPLAY 0.659574 (-1940 3910);
PAINT MONO (-1940 3910);
DISPLAY INVISIBLE (-1940 3910);
FORCEPROP 1 LASTPIN (-1950 3900) BN 3
J 0
(-1962 3908);
DISPLAY 0.680851 (-1962 3908);
PAINT GREEN (-1962 3908);
FORCEPROP 2 LAST CDS_LIB standard
J 0
(-1900 3900);
DISPLAY INVISIBLE (-1900 3900);
FORCEPROP 1 LAST BODY_TYPE PLUMBING
J 0
(-1900 3950);
DISPLAY 0.872340 (-1900 3950);
PAINT GREEN (-1900 3950);
DISPLAY INVISIBLE (-1900 3950);
FORCEPROP 1 LAST HDL_TAP TRUE
J 0
(-1575 3775);
DISPLAY 0.872340 (-1575 3775);
DISPLAY INVISIBLE (-1575 3775);
FORCEPROP 1 LAST PATH I25
J 0
(-1902 3900);
DISPLAY 0.872340 (-1902 3900);
PAINT GREEN (-1902 3900);
DISPLAY INVISIBLE (-1902 3900);
FORCEADD TAP..1
(-1700 3450);
FORCEPROP 3 LASTPIN (-1750 3450) SIG_NAME P5E_CPU1_P0_TX_C_DP<2>
J 0
(-1740 3460);
DISPLAY 0.659574 (-1740 3460);
PAINT MONO (-1740 3460);
DISPLAY INVISIBLE (-1740 3460);
FORCEPROP 1 LASTPIN (-1750 3450) BN 2
J 0
(-1762 3458);
DISPLAY 0.680851 (-1762 3458);
PAINT GREEN (-1762 3458);
FORCEPROP 2 LAST CDS_LIB standard
J 0
(-1700 3450);
DISPLAY INVISIBLE (-1700 3450);
FORCEPROP 1 LAST BODY_TYPE PLUMBING
J 0
(-1700 3500);
DISPLAY 0.872340 (-1700 3500);
PAINT GREEN (-1700 3500);
DISPLAY INVISIBLE (-1700 3500);
FORCEPROP 1 LAST HDL_TAP TRUE
J 0
(-1375 3325);
DISPLAY 0.872340 (-1375 3325);
DISPLAY INVISIBLE (-1375 3325);
FORCEPROP 1 LAST PATH I26
J 0
(-1702 3450);
DISPLAY 0.872340 (-1702 3450);
PAINT GREEN (-1702 3450);
DISPLAY INVISIBLE (-1702 3450);
FORCEADD TAP..1
(-1700 3800);
FORCEPROP 3 LASTPIN (-1750 3800) SIG_NAME P5E_CPU1_P0_TX_C_DP<3>
J 0
(-1740 3810);
DISPLAY 0.659574 (-1740 3810);
PAINT MONO (-1740 3810);
DISPLAY INVISIBLE (-1740 3810);
FORCEPROP 1 LASTPIN (-1750 3800) BN 3
J 0
(-1762 3808);
DISPLAY 0.680851 (-1762 3808);
PAINT GREEN (-1762 3808);
FORCEPROP 2 LAST CDS_LIB standard
J 0
(-1700 3800);
DISPLAY INVISIBLE (-1700 3800);
FORCEPROP 1 LAST BODY_TYPE PLUMBING
J 0
(-1700 3850);
DISPLAY 0.872340 (-1700 3850);
PAINT GREEN (-1700 3850);
DISPLAY INVISIBLE (-1700 3850);
FORCEPROP 1 LAST HDL_TAP TRUE
J 0
(-1375 3675);
DISPLAY 0.872340 (-1375 3675);
DISPLAY INVISIBLE (-1375 3675);
FORCEPROP 1 LAST PATH I27
J 0
(-1702 3800);
DISPLAY 0.872340 (-1702 3800);
PAINT GREEN (-1702 3800);
DISPLAY INVISIBLE (-1702 3800);
FORCEADD TAP..1
(-1900 4250);
FORCEPROP 3 LASTPIN (-1950 4250) SIG_NAME P5E_CPU1_P0_TX_C_DN<4>
J 0
(-1940 4260);
DISPLAY 0.659574 (-1940 4260);
PAINT MONO (-1940 4260);
DISPLAY INVISIBLE (-1940 4260);
FORCEPROP 1 LASTPIN (-1950 4250) BN 4
J 0
(-1962 4258);
DISPLAY 0.680851 (-1962 4258);
PAINT GREEN (-1962 4258);
FORCEPROP 2 LAST CDS_LIB standard
J 0
(-1900 4250);
DISPLAY INVISIBLE (-1900 4250);
FORCEPROP 1 LAST BODY_TYPE PLUMBING
J 0
(-1900 4300);
DISPLAY 0.872340 (-1900 4300);
PAINT GREEN (-1900 4300);
DISPLAY INVISIBLE (-1900 4300);
FORCEPROP 1 LAST HDL_TAP TRUE
J 0
(-1575 4125);
DISPLAY 0.872340 (-1575 4125);
DISPLAY INVISIBLE (-1575 4125);
FORCEPROP 1 LAST PATH I28
J 0
(-1902 4250);
DISPLAY 0.872340 (-1902 4250);
PAINT GREEN (-1902 4250);
DISPLAY INVISIBLE (-1902 4250);
FORCEADD TAP..1
(-1700 4150);
FORCEPROP 3 LASTPIN (-1750 4150) SIG_NAME P5E_CPU1_P0_TX_C_DP<4>
J 0
(-1740 4160);
DISPLAY 0.659574 (-1740 4160);
PAINT MONO (-1740 4160);
DISPLAY INVISIBLE (-1740 4160);
FORCEPROP 1 LASTPIN (-1750 4150) BN 4
J 0
(-1762 4158);
DISPLAY 0.680851 (-1762 4158);
PAINT GREEN (-1762 4158);
FORCEPROP 2 LAST CDS_LIB standard
J 0
(-1700 4150);
DISPLAY INVISIBLE (-1700 4150);
FORCEPROP 1 LAST BODY_TYPE PLUMBING
J 0
(-1700 4200);
DISPLAY 0.872340 (-1700 4200);
PAINT GREEN (-1700 4200);
DISPLAY INVISIBLE (-1700 4200);
FORCEPROP 1 LAST HDL_TAP TRUE
J 0
(-1375 4025);
DISPLAY 0.872340 (-1375 4025);
DISPLAY INVISIBLE (-1375 4025);
FORCEPROP 1 LAST PATH I29
J 0
(-1702 4150);
DISPLAY 0.872340 (-1702 4150);
PAINT GREEN (-1702 4150);
DISPLAY INVISIBLE (-1702 4150);
FORCEADD TAP..1
(-6525 2900);
FORCEPROP 3 LASTPIN (-6575 2900) SIG_NAME P5E_CPU1_P0_TX_C_DN<8>
J 0
(-6565 2910);
DISPLAY 0.659574 (-6565 2910);
PAINT MONO (-6565 2910);
DISPLAY INVISIBLE (-6565 2910);
FORCEPROP 1 LASTPIN (-6575 2900) BN 8
J 0
(-6587 2908);
DISPLAY 0.680851 (-6587 2908);
PAINT GREEN (-6587 2908);
FORCEPROP 2 LAST CDS_LIB standard
J 0
(-6525 2900);
DISPLAY INVISIBLE (-6525 2900);
FORCEPROP 1 LAST BODY_TYPE PLUMBING
J 0
(-6525 2950);
DISPLAY 0.872340 (-6525 2950);
PAINT GREEN (-6525 2950);
DISPLAY INVISIBLE (-6525 2950);
FORCEPROP 1 LAST HDL_TAP TRUE
J 0
(-6200 2775);
DISPLAY 0.872340 (-6200 2775);
DISPLAY INVISIBLE (-6200 2775);
FORCEPROP 1 LAST PATH I3
J 0
(-6527 2900);
DISPLAY 0.872340 (-6527 2900);
PAINT GREEN (-6527 2900);
DISPLAY INVISIBLE (-6527 2900);
FORCEADD TAP..1
(-1900 4600);
FORCEPROP 3 LASTPIN (-1950 4600) SIG_NAME P5E_CPU1_P0_TX_C_DN<5>
J 0
(-1940 4610);
DISPLAY 0.659574 (-1940 4610);
PAINT MONO (-1940 4610);
DISPLAY INVISIBLE (-1940 4610);
FORCEPROP 1 LASTPIN (-1950 4600) BN 5
J 0
(-1962 4608);
DISPLAY 0.680851 (-1962 4608);
PAINT GREEN (-1962 4608);
FORCEPROP 2 LAST CDS_LIB standard
J 0
(-1900 4600);
DISPLAY INVISIBLE (-1900 4600);
FORCEPROP 1 LAST BODY_TYPE PLUMBING
J 0
(-1900 4650);
DISPLAY 0.872340 (-1900 4650);
PAINT GREEN (-1900 4650);
DISPLAY INVISIBLE (-1900 4650);
FORCEPROP 1 LAST HDL_TAP TRUE
J 0
(-1575 4475);
DISPLAY 0.872340 (-1575 4475);
DISPLAY INVISIBLE (-1575 4475);
FORCEPROP 1 LAST PATH I30
J 0
(-1902 4600);
DISPLAY 0.872340 (-1902 4600);
PAINT GREEN (-1902 4600);
DISPLAY INVISIBLE (-1902 4600);
FORCEADD TAP..1
(-1700 4500);
FORCEPROP 3 LASTPIN (-1750 4500) SIG_NAME P5E_CPU1_P0_TX_C_DP<5>
J 0
(-1740 4510);
DISPLAY 0.659574 (-1740 4510);
PAINT MONO (-1740 4510);
DISPLAY INVISIBLE (-1740 4510);
FORCEPROP 1 LASTPIN (-1750 4500) BN 5
J 0
(-1762 4508);
DISPLAY 0.680851 (-1762 4508);
PAINT GREEN (-1762 4508);
FORCEPROP 2 LAST CDS_LIB standard
J 0
(-1700 4500);
DISPLAY INVISIBLE (-1700 4500);
FORCEPROP 1 LAST BODY_TYPE PLUMBING
J 0
(-1700 4550);
DISPLAY 0.872340 (-1700 4550);
PAINT GREEN (-1700 4550);
DISPLAY INVISIBLE (-1700 4550);
FORCEPROP 1 LAST HDL_TAP TRUE
J 0
(-1375 4375);
DISPLAY 0.872340 (-1375 4375);
DISPLAY INVISIBLE (-1375 4375);
FORCEPROP 1 LAST PATH I31
J 0
(-1702 4500);
DISPLAY 0.872340 (-1702 4500);
PAINT GREEN (-1702 4500);
DISPLAY INVISIBLE (-1702 4500);
FORCEADD TAP..1
(-1700 4850);
FORCEPROP 3 LASTPIN (-1750 4850) SIG_NAME P5E_CPU1_P0_TX_C_DP<6>
J 0
(-1740 4860);
DISPLAY 0.659574 (-1740 4860);
PAINT MONO (-1740 4860);
DISPLAY INVISIBLE (-1740 4860);
FORCEPROP 1 LASTPIN (-1750 4850) BN 6
J 0
(-1762 4858);
DISPLAY 0.680851 (-1762 4858);
PAINT GREEN (-1762 4858);
FORCEPROP 2 LAST CDS_LIB standard
J 0
(-1700 4850);
DISPLAY INVISIBLE (-1700 4850);
FORCEPROP 1 LAST BODY_TYPE PLUMBING
J 0
(-1700 4900);
DISPLAY 0.872340 (-1700 4900);
PAINT GREEN (-1700 4900);
DISPLAY INVISIBLE (-1700 4900);
FORCEPROP 1 LAST HDL_TAP TRUE
J 0
(-1375 4725);
DISPLAY 0.872340 (-1375 4725);
DISPLAY INVISIBLE (-1375 4725);
FORCEPROP 1 LAST PATH I32
J 0
(-1702 4850);
DISPLAY 0.872340 (-1702 4850);
PAINT GREEN (-1702 4850);
DISPLAY INVISIBLE (-1702 4850);
FORCEADD TAP..1
(-1900 4950);
FORCEPROP 3 LASTPIN (-1950 4950) SIG_NAME P5E_CPU1_P0_TX_C_DN<6>
J 0
(-1940 4960);
DISPLAY 0.659574 (-1940 4960);
PAINT MONO (-1940 4960);
DISPLAY INVISIBLE (-1940 4960);
FORCEPROP 1 LASTPIN (-1950 4950) BN 6
J 0
(-1962 4958);
DISPLAY 0.680851 (-1962 4958);
PAINT GREEN (-1962 4958);
FORCEPROP 2 LAST CDS_LIB standard
J 0
(-1900 4950);
DISPLAY INVISIBLE (-1900 4950);
FORCEPROP 1 LAST BODY_TYPE PLUMBING
J 0
(-1900 5000);
DISPLAY 0.872340 (-1900 5000);
PAINT GREEN (-1900 5000);
DISPLAY INVISIBLE (-1900 5000);
FORCEPROP 1 LAST HDL_TAP TRUE
J 0
(-1575 4825);
DISPLAY 0.872340 (-1575 4825);
DISPLAY INVISIBLE (-1575 4825);
FORCEPROP 1 LAST PATH I33
J 0
(-1902 4950);
DISPLAY 0.872340 (-1902 4950);
PAINT GREEN (-1902 4950);
DISPLAY INVISIBLE (-1902 4950);
FORCEADD TAP..1
(-1900 5300);
FORCEPROP 3 LASTPIN (-1950 5300) SIG_NAME P5E_CPU1_P0_TX_C_DN<7>
J 0
(-1940 5310);
DISPLAY 0.659574 (-1940 5310);
PAINT MONO (-1940 5310);
DISPLAY INVISIBLE (-1940 5310);
FORCEPROP 1 LASTPIN (-1950 5300) BN 7
J 0
(-1962 5308);
DISPLAY 0.680851 (-1962 5308);
PAINT GREEN (-1962 5308);
FORCEPROP 2 LAST CDS_LIB standard
J 0
(-1900 5300);
DISPLAY INVISIBLE (-1900 5300);
FORCEPROP 1 LAST BODY_TYPE PLUMBING
J 0
(-1900 5350);
DISPLAY 0.872340 (-1900 5350);
PAINT GREEN (-1900 5350);
DISPLAY INVISIBLE (-1900 5350);
FORCEPROP 1 LAST HDL_TAP TRUE
J 0
(-1575 5175);
DISPLAY 0.872340 (-1575 5175);
DISPLAY INVISIBLE (-1575 5175);
FORCEPROP 1 LAST PATH I34
J 0
(-1902 5300);
DISPLAY 0.872340 (-1902 5300);
PAINT GREEN (-1902 5300);
DISPLAY INVISIBLE (-1902 5300);
FORCEADD TAP..1
(-1700 5200);
FORCEPROP 3 LASTPIN (-1750 5200) SIG_NAME P5E_CPU1_P0_TX_C_DP<7>
J 0
(-1740 5210);
DISPLAY 0.659574 (-1740 5210);
PAINT MONO (-1740 5210);
DISPLAY INVISIBLE (-1740 5210);
FORCEPROP 1 LASTPIN (-1750 5200) BN 7
J 0
(-1762 5208);
DISPLAY 0.680851 (-1762 5208);
PAINT GREEN (-1762 5208);
FORCEPROP 2 LAST CDS_LIB standard
J 0
(-1700 5200);
DISPLAY INVISIBLE (-1700 5200);
FORCEPROP 1 LAST BODY_TYPE PLUMBING
J 0
(-1700 5250);
DISPLAY 0.872340 (-1700 5250);
PAINT GREEN (-1700 5250);
DISPLAY INVISIBLE (-1700 5250);
FORCEPROP 1 LAST HDL_TAP TRUE
J 0
(-1375 5075);
DISPLAY 0.872340 (-1375 5075);
DISPLAY INVISIBLE (-1375 5075);
FORCEPROP 1 LAST PATH I35
J 0
(-1702 5200);
DISPLAY 0.872340 (-1702 5200);
PAINT GREEN (-1702 5200);
DISPLAY INVISIBLE (-1702 5200);
FORCEADD OFFPAGE..1
R 2
(-700 5225);
FORCEPROP 2 LAST $XR0 65 
J 0
(-514 5225);
DISPLAY 0.638298 (-514 5225);
PAINT MONO (-514 5225);
FORCEPROP 2 LAST CDS_LIB standard
J 0
(-700 5225);
DISPLAY INVISIBLE (-700 5225);
FORCEPROP 1 LAST OFFPAGE TRUE
J 2
(-1025 5100);
DISPLAY 0.872340 (-1025 5100);
DISPLAY INVISIBLE (-1025 5100);
FORCEPROP 1 LAST COMMENT_BODY TRUE
J 2
(-825 5125);
DISPLAY 0.872340 (-825 5125);
PAINT GREEN (-825 5125);
DISPLAY INVISIBLE (-825 5125);
FORCEPROP 2 LAST PATH I36
J 0
(-525 5300);
DISPLAY 0.680851 (-525 5300);
DISPLAY INVISIBLE (-525 5300);
FORCEADD OFFPAGE..1
R 2
(-700 5325);
FORCEPROP 2 LAST $XR0 65 
J 0
(-514 5325);
DISPLAY 0.638298 (-514 5325);
PAINT MONO (-514 5325);
FORCEPROP 2 LAST CDS_LIB standard
J 2
(-700 5325);
DISPLAY INVISIBLE (-700 5325);
FORCEPROP 1 LAST OFFPAGE TRUE
J 2
(-1025 5200);
DISPLAY 0.872340 (-1025 5200);
DISPLAY INVISIBLE (-1025 5200);
FORCEPROP 1 LAST COMMENT_BODY TRUE
J 2
(-825 5225);
DISPLAY 0.872340 (-825 5225);
PAINT GREEN (-825 5225);
DISPLAY INVISIBLE (-825 5225);
FORCEPROP 2 LAST PATH I37
J 0
(-525 5400);
DISPLAY 0.680851 (-525 5400);
DISPLAY INVISIBLE (-525 5400);
FORCEADD PT5161LRS..9
(-2925 4050);
FORCEPROP 1 LAST LOCATION U6014
J 0
(-3275 5675);
DISPLAY 0.723404 (-3275 5675);
PAINT GREEN (-3275 5675);
FORCEPROP 0 LAST $SEC 9
J 0
(-3275 5825);
DISPLAY 0.680851 (-3275 5825);
PAINT MONO (-3275 5825);
DISPLAY INVISIBLE (-3275 5825);
FORCEPROP 0 LAST CDS_SEC 9
J 0
(-3275 5825);
DISPLAY 0.680851 (-3275 5825);
DISPLAY INVISIBLE (-3275 5825);
FORCEPROP 0 LASTPIN (-2475 5200) $PN CL35
J 0
(-2465 5210);
DISPLAY 0.680851 (-2465 5210);
PAINT MONO (-2465 5210);
FORCEPROP 0 LASTPIN (-2475 4850) $PN CV35
J 0
(-2465 4860);
DISPLAY 0.680851 (-2465 4860);
PAINT MONO (-2465 4860);
FORCEPROP 0 LASTPIN (-2475 4500) $PN DE35
J 0
(-2465 4510);
DISPLAY 0.680851 (-2465 4510);
PAINT MONO (-2465 4510);
FORCEPROP 0 LASTPIN (-2475 4150) $PN DM35
J 0
(-2465 4160);
DISPLAY 0.680851 (-2465 4160);
PAINT MONO (-2465 4160);
FORCEPROP 0 LASTPIN (-2475 3800) $PN DW35
J 0
(-2465 3810);
DISPLAY 0.680851 (-2465 3810);
PAINT MONO (-2465 3810);
FORCEPROP 0 LASTPIN (-2475 3450) $PN EF35
J 0
(-2465 3460);
DISPLAY 0.680851 (-2465 3460);
PAINT MONO (-2465 3460);
FORCEPROP 0 LASTPIN (-2475 3100) $PN EN35
J 0
(-2465 3110);
DISPLAY 0.680851 (-2465 3110);
PAINT MONO (-2465 3110);
FORCEPROP 0 LASTPIN (-2475 2750) $PN EY35
J 0
(-2465 2760);
DISPLAY 0.680851 (-2465 2760);
PAINT MONO (-2465 2760);
FORCEPROP 0 LASTPIN (-2475 5300) $PN CJ34
J 0
(-2465 5310);
DISPLAY 0.680851 (-2465 5310);
PAINT MONO (-2465 5310);
FORCEPROP 0 LASTPIN (-2475 4950) $PN CT34
J 0
(-2465 4960);
DISPLAY 0.680851 (-2465 4960);
PAINT MONO (-2465 4960);
FORCEPROP 0 LASTPIN (-2475 4600) $PN DC34
J 0
(-2465 4610);
DISPLAY 0.680851 (-2465 4610);
PAINT MONO (-2465 4610);
FORCEPROP 0 LASTPIN (-2475 4250) $PN DK34
J 0
(-2465 4260);
DISPLAY 0.680851 (-2465 4260);
PAINT MONO (-2465 4260);
FORCEPROP 0 LASTPIN (-2475 3900) $PN DU34
J 0
(-2465 3910);
DISPLAY 0.680851 (-2465 3910);
PAINT MONO (-2465 3910);
FORCEPROP 0 LASTPIN (-2475 3550) $PN ED34
J 0
(-2465 3560);
DISPLAY 0.680851 (-2465 3560);
PAINT MONO (-2465 3560);
FORCEPROP 0 LASTPIN (-2475 3200) $PN EL34
J 0
(-2465 3210);
DISPLAY 0.680851 (-2465 3210);
PAINT MONO (-2465 3210);
FORCEPROP 0 LASTPIN (-2475 2850) $PN EV34
J 0
(-2465 2860);
DISPLAY 0.680851 (-2465 2860);
PAINT MONO (-2465 2860);
FORCEPROP 2 LAST PART_TYPE SMLF
J 0
(-3275 5775);
DISPLAY 0.680851 (-3275 5775);
FORCEPROP 2 LAST VALUE PT5161LRS
J 0
(-3275 5725);
DISPLAY 0.680851 (-3275 5725);
FORCEPROP 1 LAST MATERIAL IC
J 0
(-3275 5525);
DISPLAY 0.723404 (-3275 5525);
PAINT GREEN (-3275 5525);
FORCEPROP 1 LAST NEEDS_NO_SIZE TRUE
J 0
(-2925 4050);
DISPLAY 0.723404 (-2925 4050);
PAINT GREEN (-2925 4050);
DISPLAY INVISIBLE (-2925 4050);
FORCEPROP 1 LAST CDS_LMAN_SYM_OUTLINE -350,1450,300,-1400
J 0
(-2925 4050);
DISPLAY 0.468085 (-2925 4050);
PAINT GREEN (-2925 4050);
DISPLAY INVISIBLE (-2925 4050);
FORCEPROP 2 LAST CDS_LIB pure_quanta
J 0
(-2925 4050);
DISPLAY INVISIBLE (-2925 4050);
FORCEPROP 1 LAST PATH I38
J 0
(-2925 4050);
DISPLAY 0.723404 (-2925 4050);
PAINT GREEN (-2925 4050);
DISPLAY INVISIBLE (-2925 4050);
FORCEPROP 1 LAST PART_NUMBER AJ051610U03
J 0
(-3275 5600);
DISPLAY 0.723404 (-3275 5600);
PAINT GREEN (-3275 5600);
DISPLAY INVISIBLE (-3275 5600);
FORCEADD TAP..1
(-6525 3250);
FORCEPROP 3 LASTPIN (-6575 3250) SIG_NAME P5E_CPU1_P0_TX_C_DN<9>
J 0
(-6565 3260);
DISPLAY 0.659574 (-6565 3260);
PAINT MONO (-6565 3260);
DISPLAY INVISIBLE (-6565 3260);
FORCEPROP 1 LASTPIN (-6575 3250) BN 9
J 0
(-6587 3258);
DISPLAY 0.680851 (-6587 3258);
PAINT GREEN (-6587 3258);
FORCEPROP 2 LAST CDS_LIB standard
J 0
(-6525 3250);
DISPLAY INVISIBLE (-6525 3250);
FORCEPROP 1 LAST BODY_TYPE PLUMBING
J 0
(-6525 3300);
DISPLAY 0.872340 (-6525 3300);
PAINT GREEN (-6525 3300);
DISPLAY INVISIBLE (-6525 3300);
FORCEPROP 1 LAST HDL_TAP TRUE
J 0
(-6200 3125);
DISPLAY 0.872340 (-6200 3125);
DISPLAY INVISIBLE (-6200 3125);
FORCEPROP 1 LAST PATH I4
J 0
(-6527 3250);
DISPLAY 0.872340 (-6527 3250);
PAINT GREEN (-6527 3250);
DISPLAY INVISIBLE (-6527 3250);
FORCEADD TAP..1
(-6325 3150);
FORCEPROP 3 LASTPIN (-6375 3150) SIG_NAME P5E_CPU1_P0_TX_C_DP<9>
J 0
(-6365 3160);
DISPLAY 0.659574 (-6365 3160);
PAINT MONO (-6365 3160);
DISPLAY INVISIBLE (-6365 3160);
FORCEPROP 1 LASTPIN (-6375 3150) BN 9
J 0
(-6387 3158);
DISPLAY 0.680851 (-6387 3158);
PAINT GREEN (-6387 3158);
FORCEPROP 2 LAST CDS_LIB standard
J 0
(-6325 3150);
DISPLAY INVISIBLE (-6325 3150);
FORCEPROP 1 LAST BODY_TYPE PLUMBING
J 0
(-6325 3200);
DISPLAY 0.872340 (-6325 3200);
PAINT GREEN (-6325 3200);
DISPLAY INVISIBLE (-6325 3200);
FORCEPROP 1 LAST HDL_TAP TRUE
J 0
(-6000 3025);
DISPLAY 0.872340 (-6000 3025);
DISPLAY INVISIBLE (-6000 3025);
FORCEPROP 1 LAST PATH I5
J 0
(-6327 3150);
DISPLAY 0.872340 (-6327 3150);
PAINT GREEN (-6327 3150);
DISPLAY INVISIBLE (-6327 3150);
FORCEADD TAP..1
(-6525 3600);
FORCEPROP 3 LASTPIN (-6575 3600) SIG_NAME P5E_CPU1_P0_TX_C_DN<10>
J 0
(-6565 3610);
DISPLAY 0.659574 (-6565 3610);
PAINT MONO (-6565 3610);
DISPLAY INVISIBLE (-6565 3610);
FORCEPROP 1 LASTPIN (-6575 3600) BN 10
J 0
(-6587 3608);
DISPLAY 0.680851 (-6587 3608);
PAINT GREEN (-6587 3608);
FORCEPROP 2 LAST CDS_LIB standard
J 0
(-6525 3600);
DISPLAY INVISIBLE (-6525 3600);
FORCEPROP 1 LAST BODY_TYPE PLUMBING
J 0
(-6525 3650);
DISPLAY 0.872340 (-6525 3650);
PAINT GREEN (-6525 3650);
DISPLAY INVISIBLE (-6525 3650);
FORCEPROP 1 LAST HDL_TAP TRUE
J 0
(-6200 3475);
DISPLAY 0.872340 (-6200 3475);
DISPLAY INVISIBLE (-6200 3475);
FORCEPROP 1 LAST PATH I6
J 0
(-6527 3600);
DISPLAY 0.872340 (-6527 3600);
PAINT GREEN (-6527 3600);
DISPLAY INVISIBLE (-6527 3600);
FORCEADD TAP..1
(-6325 3500);
FORCEPROP 3 LASTPIN (-6375 3500) SIG_NAME P5E_CPU1_P0_TX_C_DP<10>
J 0
(-6365 3510);
DISPLAY 0.659574 (-6365 3510);
PAINT MONO (-6365 3510);
DISPLAY INVISIBLE (-6365 3510);
FORCEPROP 1 LASTPIN (-6375 3500) BN 10
J 0
(-6387 3508);
DISPLAY 0.680851 (-6387 3508);
PAINT GREEN (-6387 3508);
FORCEPROP 2 LAST CDS_LIB standard
J 0
(-6325 3500);
DISPLAY INVISIBLE (-6325 3500);
FORCEPROP 1 LAST BODY_TYPE PLUMBING
J 0
(-6325 3550);
DISPLAY 0.872340 (-6325 3550);
PAINT GREEN (-6325 3550);
DISPLAY INVISIBLE (-6325 3550);
FORCEPROP 1 LAST HDL_TAP TRUE
J 0
(-6000 3375);
DISPLAY 0.872340 (-6000 3375);
DISPLAY INVISIBLE (-6000 3375);
FORCEPROP 1 LAST PATH I7
J 0
(-6327 3500);
DISPLAY 0.872340 (-6327 3500);
PAINT GREEN (-6327 3500);
DISPLAY INVISIBLE (-6327 3500);
FORCEADD TAP..1
(-6325 3850);
FORCEPROP 3 LASTPIN (-6375 3850) SIG_NAME P5E_CPU1_P0_TX_C_DP<11>
J 0
(-6365 3860);
DISPLAY 0.659574 (-6365 3860);
PAINT MONO (-6365 3860);
DISPLAY INVISIBLE (-6365 3860);
FORCEPROP 1 LASTPIN (-6375 3850) BN 11
J 0
(-6387 3858);
DISPLAY 0.680851 (-6387 3858);
PAINT GREEN (-6387 3858);
FORCEPROP 2 LAST CDS_LIB standard
J 0
(-6325 3850);
DISPLAY INVISIBLE (-6325 3850);
FORCEPROP 1 LAST BODY_TYPE PLUMBING
J 0
(-6325 3900);
DISPLAY 0.872340 (-6325 3900);
PAINT GREEN (-6325 3900);
DISPLAY INVISIBLE (-6325 3900);
FORCEPROP 1 LAST HDL_TAP TRUE
J 0
(-6000 3725);
DISPLAY 0.872340 (-6000 3725);
DISPLAY INVISIBLE (-6000 3725);
FORCEPROP 1 LAST PATH I8
J 0
(-6327 3850);
DISPLAY 0.872340 (-6327 3850);
PAINT GREEN (-6327 3850);
DISPLAY INVISIBLE (-6327 3850);
FORCEADD TAP..1
(-6525 3950);
FORCEPROP 3 LASTPIN (-6575 3950) SIG_NAME P5E_CPU1_P0_TX_C_DN<11>
J 0
(-6565 3960);
DISPLAY 0.659574 (-6565 3960);
PAINT MONO (-6565 3960);
DISPLAY INVISIBLE (-6565 3960);
FORCEPROP 1 LASTPIN (-6575 3950) BN 11
J 0
(-6587 3958);
DISPLAY 0.680851 (-6587 3958);
PAINT GREEN (-6587 3958);
FORCEPROP 2 LAST CDS_LIB standard
J 0
(-6525 3950);
DISPLAY INVISIBLE (-6525 3950);
FORCEPROP 1 LAST BODY_TYPE PLUMBING
J 0
(-6525 4000);
DISPLAY 0.872340 (-6525 4000);
PAINT GREEN (-6525 4000);
DISPLAY INVISIBLE (-6525 4000);
FORCEPROP 1 LAST HDL_TAP TRUE
J 0
(-6200 3825);
DISPLAY 0.872340 (-6200 3825);
DISPLAY INVISIBLE (-6200 3825);
FORCEPROP 1 LAST PATH I9
J 0
(-6527 3950);
DISPLAY 0.872340 (-6527 3950);
PAINT GREEN (-6527 3950);
DISPLAY INVISIBLE (-6527 3950);
FORCEADD QUANTA_TITLE_BLOCK_C..1
(0 0);
FORCEPROP 0 LAST CDS_CON_LAST_MODIFIED Thu Sep 14 16:12:54 2023
J 0
(-1885 15);
DISPLAY INVISIBLE (-1885 15);
FORCEPROP 1 LAST CUSTOM_TXT_CDS <CON_LAST_MODIFIED>
J 0
(-1885 15);
DISPLAY 0.978723 (-1885 15);
FORCEPROP 2 LAST CUSTOM_TXT_CDS <XR_PAGE_TITLE>
J 0
(-7890 5250);
DISPLAY 0.638298 (-7890 5250);
PAINT PINK (-7890 5250);
DISPLAY INVISIBLE (-7890 5250);
FORCEPROP 1 LAST CUSTOM_TXT_CDS <NAME_2>
J 0
(-3175 50);
FORCEPROP 1 LAST CUSTOM_TXT_CDS <NAME_1>
J 0
(-3175 175);
FORCEPROP 1 LAST CUSTOM_TXT_CDS <Q_NUMBER>
J 0
(-1403 103);
DISPLAY 1.212766 (-1403 103);
FORCEPROP 1 LAST CUSTOM_TXT_CDS <Q_PROJ>
J 0
(-2382 102);
DISPLAY 1.212766 (-2382 102);
FORCEPROP 1 LAST CUSTOM_TXT_CDS <Q_REV>
J 0
(-184 103);
DISPLAY 1.212766 (-184 103);
FORCEPROP 1 LAST CUSTOM_TXT_CDS <CON_PAGE_NUM> OF <CON_TOTAL_PAGES>
J 0
(-446 18);
DISPLAY 0.978723 (-446 18);
FORCEPROP 1 LAST Q_TITLE RETIMER_CPU1_P0(1)
J 0
(-9366 26);
DISPLAY 2.446809 (-9366 26);
PAINT GREEN (-9366 26);
FORCEPROP 2 LAST CDS_LIB pure_quanta
J 0
(0 0);
DISPLAY INVISIBLE (0 0);
FORCEPROP 1 LAST CDS_LMAN_SYM_OUTLINE -9475,6775,100,-125
J 0
(0 0);
DISPLAY 0.468085 (0 0);
PAINT GREEN (0 0);
DISPLAY INVISIBLE (0 0);
FORCEPROP 2 LAST PAGE_BORDER TRUE
J 0
(-7890 5250);
DISPLAY 0.638298 (-7890 5250);
PAINT PINK (-7890 5250);
DISPLAY INVISIBLE (-7890 5250);
FORCEPROP 2 LAST CDS_XR_PAGE_TITLE CR-317 : @T6G_MB_LIB.T6G(SCH_1):PAGE317
J 0
(-7890 5250);
DISPLAY 0.638298 (-7890 5250);
PAINT PINK (-7890 5250);
DISPLAY INVISIBLE (-7890 5250);
FORCEPROP 1 LAST Q_DEPT BU9
J 1
(-3763 49);
DISPLAY 1.957447 (-3763 49);
PAINT GREEN (-3763 49);
DISPLAY INVISIBLE (-3763 49);
FORCEPROP 1 LAST COMMENT_BODY TRUE
J 0
(12 -13);
DISPLAY 0.978723 (12 -13);
PAINT GREEN (12 -13);
DISPLAY INVISIBLE (12 -13);
WIRE 17 -1 (-1850 3925)(-1850 4275);
WIRE 17 -1 (-1850 3925)(-1850 3575);
WIRE 17 -1 (-1850 4625)(-1850 4275);
WIRE 17 -1 (-1850 4975)(-1850 4625);
WIRE 17 -1 (-1850 3575)(-1850 3125);
WIRE 17 -1 (-1850 3125)(-1850 2875);
WIRE 17 -1 (-1850 5325)(-1850 4975);
WIRE 17 -1 (-1850 5325)(-750 5325);
FORCEPROP 2 LAST SIG_NAME P5E_CPU1_P0_TX_C_DN<7:0>
J 0
(-1585 5335);
DISPLAY 0.680851 (-1585 5335);
PAINT WHITE (-1585 5335);
WIRE 17 -1 (-1650 4525)(-1650 4175);
WIRE 17 -1 (-1650 4875)(-1650 4525);
WIRE 17 -1 (-1650 3825)(-1650 4175);
WIRE 17 -1 (-1650 3825)(-1650 3475);
WIRE 17 -1 (-1650 5225)(-1650 4875);
WIRE 17 -1 (-1650 5225)(-750 5225);
FORCEPROP 2 LAST SIG_NAME P5E_CPU1_P0_TX_C_DP<7:0>
J 0
(-1585 5235);
DISPLAY 0.680851 (-1585 5235);
PAINT WHITE (-1585 5235);
WIRE 17 -1 (-1650 3475)(-1650 3225);
WIRE 17 -1 (-1650 3225)(-1650 2775);
WIRE 17 -1 (-6275 3175)(-6275 2825);
WIRE 17 -1 (-6275 3525)(-6275 3175);
WIRE 17 -1 (-6275 3875)(-6275 3525);
WIRE 17 -1 (-6275 3875)(-6275 4225);
WIRE 17 -1 (-6275 4675)(-6275 4225);
WIRE 17 -1 (-6275 4925)(-6275 4675);
WIRE 17 -1 (-6275 5275)(-6275 4925);
WIRE 17 -1 (-6275 5275)(-5375 5275);
FORCEPROP 2 LAST SIG_NAME P5E_CPU1_P0_TX_C_DP<15:8>
J 0
(-6210 5285);
DISPLAY 0.680851 (-6210 5285);
PAINT WHITE (-6210 5285);
WIRE 17 -1 (-6475 3275)(-6475 2925);
WIRE 17 -1 (-6475 3625)(-6475 3275);
WIRE 17 -1 (-6475 3975)(-6475 3625);
WIRE 17 -1 (-6475 3975)(-6475 4325);
WIRE 17 -1 (-6475 4575)(-6475 4325);
WIRE 17 -1 (-6475 5025)(-6475 4575);
WIRE 17 -1 (-6475 5375)(-6475 5025);
WIRE 17 -1 (-6475 5375)(-5375 5375);
FORCEPROP 2 LAST SIG_NAME P5E_CPU1_P0_TX_C_DN<15:8>
J 0
(-6210 5385);
DISPLAY 0.680851 (-6210 5385);
PAINT WHITE (-6210 5385);
WIRE 16 -1 (-7100 4550)(-6575 4550);
WIRE 16 -1 (-7100 4650)(-6375 4650);
WIRE 16 -1 (-7100 5250)(-6375 5250);
WIRE 16 -1 (-7100 4900)(-6375 4900);
WIRE 16 -1 (-7100 5350)(-6575 5350);
WIRE 16 -1 (-7100 5000)(-6575 5000);
WIRE 16 -1 (-7100 3250)(-6575 3250);
WIRE 16 -1 (-7100 3600)(-6575 3600);
WIRE 16 -1 (-7100 3950)(-6575 3950);
WIRE 16 -1 (-7100 4300)(-6575 4300);
WIRE 16 -1 (-7100 2900)(-6575 2900);
WIRE 16 -1 (-2475 3200)(-1750 3200);
WIRE 16 -1 (-1950 3100)(-2475 3100);
WIRE 16 -1 (-2475 3450)(-1750 3450);
WIRE 16 -1 (-2475 2850)(-1950 2850);
WIRE 16 -1 (-2475 2750)(-1750 2750);
WIRE 16 -1 (-2475 3550)(-1950 3550);
WIRE 16 -1 (-2475 5300)(-1950 5300);
WIRE 16 -1 (-7100 3150)(-6375 3150);
WIRE 16 -1 (-2475 4500)(-1750 4500);
WIRE 16 -1 (-2475 4600)(-1950 4600);
WIRE 16 -1 (-7100 4200)(-6375 4200);
WIRE 16 -1 (-7100 3500)(-6375 3500);
WIRE 16 -1 (-7100 3850)(-6375 3850);
WIRE 16 -1 (-7100 2800)(-6375 2800);
WIRE 16 -1 (-2475 3800)(-1750 3800);
WIRE 16 -1 (-2475 5200)(-1750 5200);
WIRE 16 -1 (-2475 4850)(-1750 4850);
WIRE 16 -1 (-2475 4950)(-1950 4950);
WIRE 16 -1 (-2475 4250)(-1950 4250);
WIRE 16 -1 (-2475 4150)(-1750 4150);
WIRE 16 -1 (-2475 3900)(-1950 3900);
FORCENOTE
CPU TO RETIMER
(-3375 1950) 0;
DISPLAY LEFT (-3375 1950);
DISPLAY 3.148936 (-3375 1950);
FORCENOTE
CPU TO RETIMER
(-7975 1950) 0;
DISPLAY LEFT (-7975 1950);
DISPLAY 3.148936 (-7975 1950);
FORCENOTE
P/N SWAP
(-1525 3500) 0;
DISPLAY LEFT (-1525 3500);
DISPLAY 1.021277 (-1525 3500);
FORCENOTE
P/N SWAP
(-1525 3825) 0;
DISPLAY LEFT (-1525 3825);
DISPLAY 1.021277 (-1525 3825);
FORCENOTE
P/N SWAP
(-1550 4150) 0;
DISPLAY LEFT (-1550 4150);
DISPLAY 1.021277 (-1550 4150);
FORCENOTE
P/N SWAP
(-1525 4850) 0;
DISPLAY LEFT (-1525 4850);
DISPLAY 1.021277 (-1525 4850);
FORCENOTE
P/N SWAP
(-1550 4525) 0;
DISPLAY LEFT (-1550 4525);
DISPLAY 1.021277 (-1550 4525);
FORCENOTE
P/N SWAP
(-1525 5125) 0;
DISPLAY LEFT (-1525 5125);
DISPLAY 1.021277 (-1525 5125);
FORCENOTE
P/N SWAP
(-6150 2825) 0;
DISPLAY LEFT (-6150 2825);
DISPLAY 1.021277 (-6150 2825);
FORCENOTE
P/N SWAP
(-6175 3200) 0;
DISPLAY LEFT (-6175 3200);
DISPLAY 1.021277 (-6175 3200);
FORCENOTE
P/N SWAP
(-6175 3525) 0;
DISPLAY LEFT (-6175 3525);
DISPLAY 1.021277 (-6175 3525);
FORCENOTE
P/N SWAP
(-6150 3875) 0;
DISPLAY LEFT (-6150 3875);
DISPLAY 1.021277 (-6150 3875);
FORCENOTE
P/N SWAP
(-6175 4225) 0;
DISPLAY LEFT (-6175 4225);
DISPLAY 1.021277 (-6175 4225);
FORCENOTE
P5E_CPU1_P0_TX_C_DP/DN<0-15> LANE REVERSAL
(-9100 6325) 0;
DISPLAY LEFT (-9100 6325);
DISPLAY 2.000000 (-9100 6325);
FORCENOTE
P/N SWAP
(-1500 2775) 0;
DISPLAY LEFT (-1500 2775);
DISPLAY 1.021277 (-1500 2775);
FORCENOTE
P/N SWAP
(-6175 5175) 0;
DISPLAY LEFT (-6175 5175);
DISPLAY 1.021277 (-6175 5175);
FORCENOTE
P/N SWAP
(-6175 4900) 0;
DISPLAY LEFT (-6175 4900);
DISPLAY 1.021277 (-6175 4900);
QUIT
